(kicad_pcb
	(version 20260206)
	(generator "pcbnew")
	(generator_version "10.0")
	(general
		(thickness 1.6)
		(legacy_teardrops no)
	)
	(paper "A4")
	(title_block
		(title "04192023_DAF0TMB3IC0_F0TG_MB_C_brd_V02_OCP.brd")
		(comment 1 "Grand Teton / footprint 2350 of 8354 (J19), pads 227-291 of 291")
	)
	(layers
		(0 "F.Cu" signal "TOP")
		(4 "In1.Cu" signal "GND")
		(6 "In2.Cu" signal "IN1")
		(8 "In3.Cu" signal "GND1")
		(10 "In4.Cu" signal "IN2")
		(12 "In5.Cu" signal "GND2")
		(14 "In6.Cu" signal "IN3")
		(16 "In7.Cu" signal "GND3")
		(18 "In8.Cu" signal "VCC")
		(20 "In9.Cu" signal "VCC1")
		(22 "In10.Cu" signal "GND4")
		(24 "In11.Cu" signal "IN4")
		(26 "In12.Cu" signal "GND5")
		(28 "In13.Cu" signal "IN5")
		(30 "In14.Cu" signal "GND6")
		(32 "In15.Cu" signal "IN6")
		(34 "In16.Cu" signal "GND7")
		(2 "B.Cu" signal "BOTTOM")
		(9 "F.Adhes" user "F.Adhesive")
		(11 "B.Adhes" user "B.Adhesive")
		(13 "F.Paste" user "Package Geometry/Pastemask Top")
		(15 "B.Paste" user "Package Geometry/Pastemask Bottom")
		(5 "F.SilkS" user "Ref Des/Silkscreen Top")
		(7 "B.SilkS" user "Ref Des/Silkscreen Bottom")
		(1 "F.Mask" user "Board Geometry/Soldermask Top")
		(3 "B.Mask" user "Board Geometry/Soldermask Bottom")
		(17 "Dwgs.User" user "User.Drawings")
		(19 "Cmts.User" user "User.Comments")
		(21 "Eco1.User" user "User.Eco1")
		(23 "Eco2.User" user "User.Eco2")
		(25 "Edge.Cuts" user "Board Geometry/Outline")
		(27 "Margin" user)
		(31 "F.CrtYd" user "Package Geometry/Place Bound Top")
		(29 "B.CrtYd" user "Package Geometry/Place Bound Bottom")
		(35 "F.Fab" user "Ref Des/Assembly Top")
		(33 "B.Fab" user "Ref Des/Assembly Bottom")
	)
	(footprint ""
		(layer "F.Cu")
		(at 282.685998 -255.560068 180)
		(property "Reference" "J19"
			(at -2.2098 -81.984088 0)
			(unlocked yes)
			(layer "F.SilkS")
			(effects
				(font
					(size 0.7874 0.5842)
					(thickness 0.1524)
				)
			)
		)
		(property "Value" ""
			(at 0 0 180)
			(layer "F.Fab")
			(effects
				(font
					(size 1.27 1.27)
				)
			)
		)
		(duplicate_pad_numbers_are_jumpers no)
		(pad "227" smd rect
			(at 2.050034 11.474958 90)
			(size 0.519938 1.4986)
			(layers "F.Cu" "F.Mask" "F.Paste")
			(net "M_D_CPU0_SB_PAR")
		)
		(pad "228" smd rect
			(at 2.050034 12.325096 90)
			(size 0.519938 1.4986)
			(layers "F.Cu" "F.Mask" "F.Paste")
			(net "GND")
		)
		(pad "229" smd rect
			(at 2.050034 13.17498 90)
			(size 0.519938 1.4986)
			(layers "F.Cu" "F.Mask" "F.Paste")
			(net "M_D_CPU0_SB_CS_N<1>")
		)
		(pad "230" smd rect
			(at 2.050034 14.025118 90)
			(size 0.519938 1.4986)
			(layers "F.Cu" "F.Mask" "F.Paste")
			(net "GND")
		)
		(pad "231" smd rect
			(at 2.050034 14.875002 90)
			(size 0.519938 1.4986)
			(layers "F.Cu" "F.Mask" "F.Paste")
			(net "Net_2296")
		)
		(pad "232" smd rect
			(at 2.050034 15.724886 90)
			(size 0.519938 1.4986)
			(layers "F.Cu" "F.Mask" "F.Paste")
			(net "Net_2297")
		)
		(pad "233" smd rect
			(at 2.050034 16.575024 90)
			(size 0.519938 1.4986)
			(layers "F.Cu" "F.Mask" "F.Paste")
			(net "GND")
		)
		(pad "234" smd rect
			(at 2.050034 17.424908 90)
			(size 0.519938 1.4986)
			(layers "F.Cu" "F.Mask" "F.Paste")
			(net "M_D_CPU0_SB_CB<6>")
		)
		(pad "235" smd rect
			(at 2.050034 18.275046 90)
			(size 0.519938 1.4986)
			(layers "F.Cu" "F.Mask" "F.Paste")
			(net "GND")
		)
		(pad "236" smd rect
			(at 2.050034 19.12493 90)
			(size 0.519938 1.4986)
			(layers "F.Cu" "F.Mask" "F.Paste")
			(net "M_D_CPU0_SB_CB<7>")
		)
		(pad "237" smd rect
			(at 2.050034 19.975068 90)
			(size 0.519938 1.4986)
			(layers "F.Cu" "F.Mask" "F.Paste")
			(net "GND")
		)
		(pad "238" smd rect
			(at 2.050034 20.824952 90)
			(size 0.519938 1.4986)
			(layers "F.Cu" "F.Mask" "F.Paste")
			(net "M_D_CPU0_SB_DQS_DN<4>")
		)
		(pad "239" smd rect
			(at 2.050034 21.67509 90)
			(size 0.519938 1.4986)
			(layers "F.Cu" "F.Mask" "F.Paste")
			(net "M_D_CPU0_SB_DQS_DP<4>")
		)
		(pad "240" smd rect
			(at 2.050034 22.524974 90)
			(size 0.519938 1.4986)
			(layers "F.Cu" "F.Mask" "F.Paste")
			(net "GND")
		)
		(pad "241" smd rect
			(at 2.050034 23.375112 90)
			(size 0.519938 1.4986)
			(layers "F.Cu" "F.Mask" "F.Paste")
			(net "M_D_CPU0_SB_CB<2>")
		)
		(pad "242" smd rect
			(at 2.050034 24.224996 90)
			(size 0.519938 1.4986)
			(layers "F.Cu" "F.Mask" "F.Paste")
			(net "GND")
		)
		(pad "243" smd rect
			(at 2.050034 25.07488 90)
			(size 0.519938 1.4986)
			(layers "F.Cu" "F.Mask" "F.Paste")
			(net "M_D_CPU0_SB_CB<3>")
		)
		(pad "244" smd rect
			(at 2.050034 25.925018 90)
			(size 0.519938 1.4986)
			(layers "F.Cu" "F.Mask" "F.Paste")
			(net "GND")
		)
		(pad "245" smd rect
			(at 2.050034 26.774902 90)
			(size 0.519938 1.4986)
			(layers "F.Cu" "F.Mask" "F.Paste")
			(net "M_D_CPU0_SB_DQ<2>")
		)
		(pad "246" smd rect
			(at 2.050034 27.62504 90)
			(size 0.519938 1.4986)
			(layers "F.Cu" "F.Mask" "F.Paste")
			(net "GND")
		)
		(pad "247" smd rect
			(at 2.050034 28.474924 90)
			(size 0.519938 1.4986)
			(layers "F.Cu" "F.Mask" "F.Paste")
			(net "M_D_CPU0_SB_DQ<3>")
		)
		(pad "248" smd rect
			(at 2.050034 29.325062 90)
			(size 0.519938 1.4986)
			(layers "F.Cu" "F.Mask" "F.Paste")
			(net "GND")
		)
		(pad "249" smd rect
			(at 2.050034 30.174946 90)
			(size 0.519938 1.4986)
			(layers "F.Cu" "F.Mask" "F.Paste")
			(net "M_D_CPU0_SB_DQS_DN<5>")
		)
		(pad "250" smd rect
			(at 2.050034 31.025084 90)
			(size 0.519938 1.4986)
			(layers "F.Cu" "F.Mask" "F.Paste")
			(net "M_D_CPU0_SB_DQS_DP<5>")
		)
		(pad "251" smd rect
			(at 2.050034 31.874968 90)
			(size 0.519938 1.4986)
			(layers "F.Cu" "F.Mask" "F.Paste")
			(net "GND")
		)
		(pad "252" smd rect
			(at 2.050034 32.725106 90)
			(size 0.519938 1.4986)
			(layers "F.Cu" "F.Mask" "F.Paste")
			(net "M_D_CPU0_SB_DQ<6>")
		)
		(pad "253" smd rect
			(at 2.050034 33.57499 90)
			(size 0.519938 1.4986)
			(layers "F.Cu" "F.Mask" "F.Paste")
			(net "GND")
		)
		(pad "254" smd rect
			(at 2.050034 34.425128 90)
			(size 0.519938 1.4986)
			(layers "F.Cu" "F.Mask" "F.Paste")
			(net "M_D_CPU0_SB_DQ<7>")
		)
		(pad "255" smd rect
			(at 2.050034 35.275012 90)
			(size 0.519938 1.4986)
			(layers "F.Cu" "F.Mask" "F.Paste")
			(net "GND")
		)
		(pad "256" smd rect
			(at 2.050034 36.124896 90)
			(size 0.519938 1.4986)
			(layers "F.Cu" "F.Mask" "F.Paste")
			(net "M_D_CPU0_SB_DQ<10>")
		)
		(pad "257" smd rect
			(at 2.050034 36.975034 90)
			(size 0.519938 1.4986)
			(layers "F.Cu" "F.Mask" "F.Paste")
			(net "GND")
		)
		(pad "258" smd rect
			(at 2.050034 37.824918 90)
			(size 0.519938 1.4986)
			(layers "F.Cu" "F.Mask" "F.Paste")
			(net "M_D_CPU0_SB_DQ<11>")
		)
		(pad "259" smd rect
			(at 2.050034 38.675056 90)
			(size 0.519938 1.4986)
			(layers "F.Cu" "F.Mask" "F.Paste")
			(net "GND")
		)
		(pad "260" smd rect
			(at 2.050034 39.52494 90)
			(size 0.519938 1.4986)
			(layers "F.Cu" "F.Mask" "F.Paste")
			(net "M_D_CPU0_SB_DQS_DN<6>")
		)
		(pad "261" smd rect
			(at 2.050034 40.375078 90)
			(size 0.519938 1.4986)
			(layers "F.Cu" "F.Mask" "F.Paste")
			(net "M_D_CPU0_SB_DQS_DP<6>")
		)
		(pad "262" smd rect
			(at 2.050034 41.224962 90)
			(size 0.519938 1.4986)
			(layers "F.Cu" "F.Mask" "F.Paste")
			(net "GND")
		)
		(pad "263" smd rect
			(at 2.050034 42.0751 90)
			(size 0.519938 1.4986)
			(layers "F.Cu" "F.Mask" "F.Paste")
			(net "M_D_CPU0_SB_DQ<14>")
		)
		(pad "264" smd rect
			(at 2.050034 42.924984 90)
			(size 0.519938 1.4986)
			(layers "F.Cu" "F.Mask" "F.Paste")
			(net "GND")
		)
		(pad "265" smd rect
			(at 2.050034 43.775122 90)
			(size 0.519938 1.4986)
			(layers "F.Cu" "F.Mask" "F.Paste")
			(net "M_D_CPU0_SB_DQ<15>")
		)
		(pad "266" smd rect
			(at 2.050034 44.625006 90)
			(size 0.519938 1.4986)
			(layers "F.Cu" "F.Mask" "F.Paste")
			(net "GND")
		)
		(pad "267" smd rect
			(at 2.050034 45.47489 90)
			(size 0.519938 1.4986)
			(layers "F.Cu" "F.Mask" "F.Paste")
			(net "M_D_CPU0_SB_DQ<18>")
		)
		(pad "268" smd rect
			(at 2.050034 46.325028 90)
			(size 0.519938 1.4986)
			(layers "F.Cu" "F.Mask" "F.Paste")
			(net "GND")
		)
		(pad "269" smd rect
			(at 2.050034 47.174912 90)
			(size 0.519938 1.4986)
			(layers "F.Cu" "F.Mask" "F.Paste")
			(net "M_D_CPU0_SB_DQ<19>")
		)
		(pad "270" smd rect
			(at 2.050034 48.02505 90)
			(size 0.519938 1.4986)
			(layers "F.Cu" "F.Mask" "F.Paste")
			(net "GND")
		)
		(pad "271" smd rect
			(at 2.050034 48.874934 90)
			(size 0.519938 1.4986)
			(layers "F.Cu" "F.Mask" "F.Paste")
			(net "M_D_CPU0_SB_DQS_DN<7>")
		)
		(pad "272" smd rect
			(at 2.050034 49.725072 90)
			(size 0.519938 1.4986)
			(layers "F.Cu" "F.Mask" "F.Paste")
			(net "M_D_CPU0_SB_DQS_DP<7>")
		)
		(pad "273" smd rect
			(at 2.050034 50.574956 90)
			(size 0.519938 1.4986)
			(layers "F.Cu" "F.Mask" "F.Paste")
			(net "GND")
		)
		(pad "274" smd rect
			(at 2.050034 51.425094 90)
			(size 0.519938 1.4986)
			(layers "F.Cu" "F.Mask" "F.Paste")
			(net "M_D_CPU0_SB_DQ<22>")
		)
		(pad "275" smd rect
			(at 2.050034 52.274978 90)
			(size 0.519938 1.4986)
			(layers "F.Cu" "F.Mask" "F.Paste")
			(net "GND")
		)
		(pad "276" smd rect
			(at 2.050034 53.125116 90)
			(size 0.519938 1.4986)
			(layers "F.Cu" "F.Mask" "F.Paste")
			(net "M_D_CPU0_SB_DQ<23>")
		)
		(pad "277" smd rect
			(at 2.050034 53.975 90)
			(size 0.519938 1.4986)
			(layers "F.Cu" "F.Mask" "F.Paste")
			(net "GND")
		)
		(pad "278" smd rect
			(at 2.050034 54.824884 90)
			(size 0.519938 1.4986)
			(layers "F.Cu" "F.Mask" "F.Paste")
			(net "M_D_CPU0_SB_DQ<26>")
		)
		(pad "279" smd rect
			(at 2.050034 55.675022 90)
			(size 0.519938 1.4986)
			(layers "F.Cu" "F.Mask" "F.Paste")
			(net "GND")
		)
		(pad "280" smd rect
			(at 2.050034 56.524906 90)
			(size 0.519938 1.4986)
			(layers "F.Cu" "F.Mask" "F.Paste")
			(net "M_D_CPU0_SB_DQ<27>")
		)
		(pad "281" smd rect
			(at 2.050034 57.375044 90)
			(size 0.519938 1.4986)
			(layers "F.Cu" "F.Mask" "F.Paste")
			(net "GND")
		)
		(pad "282" smd rect
			(at 2.050034 58.224928 90)
			(size 0.519938 1.4986)
			(layers "F.Cu" "F.Mask" "F.Paste")
			(net "M_D_CPU0_SB_DQS_DN<8>")
		)
		(pad "283" smd rect
			(at 2.050034 59.075066 90)
			(size 0.519938 1.4986)
			(layers "F.Cu" "F.Mask" "F.Paste")
			(net "M_D_CPU0_SB_DQS_DP<8>")
		)
		(pad "284" smd rect
			(at 2.050034 59.92495 90)
			(size 0.519938 1.4986)
			(layers "F.Cu" "F.Mask" "F.Paste")
			(net "GND")
		)
		(pad "285" smd rect
			(at 2.050034 60.775088 90)
			(size 0.519938 1.4986)
			(layers "F.Cu" "F.Mask" "F.Paste")
			(net "M_D_CPU0_SB_DQ<30>")
		)
		(pad "286" smd rect
			(at 2.050034 61.624972 90)
			(size 0.519938 1.4986)
			(layers "F.Cu" "F.Mask" "F.Paste")
			(net "GND")
		)
		(pad "287" smd rect
			(at 2.050034 62.47511 90)
			(size 0.519938 1.4986)
			(layers "F.Cu" "F.Mask" "F.Paste")
			(net "M_D_CPU0_SB_DQ<31>")
		)
		(pad "288" smd rect
			(at 2.050034 63.324994 90)
			(size 0.519938 1.4986)
			(layers "F.Cu" "F.Mask" "F.Paste")
			(net "GND")
		)
		(pad "G1" thru_hole oval
			(at 0 -68.97497 90)
			(size 1.7272 3.4798)
			(drill oval 1.2192 2.4638)
			(layers "*.Cu" "*.Mask")
			(remove_unused_layers no)
			(net "GND")
			(clearance 0.127)
			(thermal_gap 0.127)
		)
		(pad "G2" thru_hole oval
			(at 0 3.875024 90)
			(size 1.7272 3.4798)
			(drill oval 1.2192 2.4638)
			(layers "*.Cu" "*.Mask")
			(remove_unused_layers no)
			(net "GND")
			(clearance 0.127)
			(thermal_gap 0.127)
		)
		(pad "G3" thru_hole oval
			(at 0 68.97497 90)
			(size 1.7272 3.4798)
			(drill oval 1.2192 2.4638)
			(layers "*.Cu" "*.Mask")
			(remove_unused_layers no)
			(net "GND")
			(clearance 0.127)
			(thermal_gap 0.127)
		)
	)
)
